FILE_TYPE = CONNECTIVITY;
{Allegro Design Entry HDL 17.2-2016 S081 (4005846) 1/11/2022}
"PAGE_NUMBER" = 186;
0"NC";
1"GND\g";
2"GND\g";
3"GND\g";
4"GND\g";
5"GND\g";
6"P5V_STBY\g";
7"P3V3_STBY\g";
8"GND\g";
9"GND\g";
10"GND\g";
11"GND\g";
12"GND\g";
13"PVDDCR_CPU0_P1\g";
14"SW_P12V_STBY_PVDDCR_CPU0_P1_FLT\g";
15"GND\g";
16"GND\g";
17"PVDDCR_CPU0_P1\g";
18"SW_PVDDCR_CPU0_P1_BOOT2_RC";
19"SW_PVDDCR_CPU0_P1_PH1";
20"SW_PVDDCR_CPU0_P1_SW1";
21"P12V_STBY\g";
22"IND_CPU0_P1_CPL1";
23"GND\g";
24"IND_CPU0_P1_CPL2";
25"IND_CPU0_P1_CPL5";
26"SW_PVDDCR_CPU0_P1_BOOT1";
27"NC_PVDDCR_CPU0_P1_GL1_1";
28"NC_PVDDCR_CPU0_P1_GL2_1";
29"NC_PVDDCR_CPU0_P1_DNC1";
30"PVDDCR_CPU0_P1_IMON1";
31"SW_PVDDCR_CPU0_P1_BOOT2";
32"GND\g";
33"SW_PVDDCR_CPU0_P1_SW2_RC";
34"GND\g";
35"NC_PVDDCR_CPU0_P1_GL1_2";
36"NC_PVDDCR_CPU0_P1_GL2_2";
37"PVDDCR_CPU0_P1_TEMP0";
38"PVDDCR_CPU0_P1_PWM1";
39"PVDDCR_CPU0_P1_PVCC\g";
40"PVDDCR_CPU0_P1_VCC2";
41"NC_PVDDCR_CPU0_P1_DNC2";
42"PVDDCR_CPU0_P1_PWM2";
43"PVDDCR_CPU0_P1_TEMP0";
44"PVDDCR_CPU0_P1_IMON2";
45"PVDDCR_CPU0_P1_VCCS";
46"PVDDCR_CPU0_P1_LSET2";
47"SW_PVDDCR_CPU0_P1_SW1_RC";
48"IND_CPU0_P1_CPL1";
49"SW_PVDDCR_CPU0_P1_SW2";
50"PVDDCR_CPU0_P1_VOS2";
51"SW_PVDDCR_CPU0_P1_PH2";
52"SW_P12V_STBY_PVDDCR_CPU0_P1_FLT\g";
53"GND\g";
54"SW_PVDDCR_CPU0_P1_BOOT1_RC";
55"PVDDCR_CPU0_P1_VCC1";
56"PVDDCR_CPU0_P1\g";
57"PVDDCR_CPU0_P1_PVCC\g";
58"PVDDCR_CPU0_P1_VCCS";
59"PVDDCR_CPU0_P1_LSET1";
60"PVDDCR_CPU0_P1_VOS1";
61"GND\g";
%"ISL99390FRZTR5935"
"1","(-6175,4450)","0","pure_quanta","I1";
;
LOCATION"PU4"
$SEC"1"
CDS_SEC"1"
PART_TYPE"SMLF"
MATERIAL"IC"
VALUE"ISL99390FRZ-TR5935"
PART_NUMBER"AL099390004"
NEEDS_NO_SIZE"TRUE"
CDS_LMAN_SYM_OUTLINE"-300,700,250,-650"
CDS_LIB"pure_quanta";
"PGND2"
$PN"7_9-20_24"32;
"GL2"
$PN"41"28;
"GL1"
$PN"6"27;
"DNC"
$PN"31"29;
"EN"
$PN"35"55;
"PGND3"
$PN"40"32;
"VOS"
$PN"1"60;
"VIN2"
$PN"30"52;
"PGND1"
$PN"5"32;
"SW"
$PN"10_19"20;
"LSET"
$PN"37"59;
"IOUT"
$PN"38"30;
"TOUT_FLT"
$PN"36"37;
"PVCC"
$PN"4"57;
"PHASE"
$PN"32"19;
"VIN1"
$PN"25_29"52;
"BOOT"
$PN"33"26;
"AGND"
$PN"2"32;
"VCC"
$PN"3"55;
"REFIN"
$PN"39"58;
"PWM"
$PN"34"38;
%"Q_CAPP"
"1","(-2475,2900)","0","pure_quanta","I106";
;
LOCATION"PC276"
$SEC"1"
CDS_SEC"1"
VALUE"220UF"
TOLERANCE"20%"
VOLTAGE"4V"
MATERIAL"SPCAP"
PACK_TYPE"SMLF"
PART_NUMBER"CH122KM8801"
CDS_LIB"pure_quanta";
"A"
$PN"1"56;
"B"
$PN"2"15;
%"Q_CAPP"
"1","(-2800,2900)","0","pure_quanta","I107";
;
LOCATION"PC275"
$SEC"1"
CDS_SEC"1"
VALUE"220UF"
TOLERANCE"20%"
VOLTAGE"4V"
MATERIAL"SPCAP"
PACK_TYPE"SMLF"
PART_NUMBER"CH122KM8801"
CDS_LIB"pure_quanta";
"A"
$PN"1"56;
"B"
$PN"2"15;
%"VCC_CORE"
"1","(-1850,3200)","0","pure_quanta_power","I109";
;
HDL_POWER"PVDDCR_CPU0_P1"
CDS_LIB"pure_quanta_power";
"A"56;
%"Q_RES"
"1","(-7350,4150)","0","pure_quanta","I11";
;
LOCATION"PR187"
$SEC"1"
CDS_SEC"1"
WATTAGE"1/16W"
MATERIAL"EMPTY"
TOLERANCE"1%"
VALUE"8.87K"
PART_NUMBER"CS28872FB01"
PACK_TYPE"0402LF"
CDS_LIB"pure_quanta";
"B"
$PN"2"59;
"A"
$PN"1"3;
%"UNIVERSAL_GND"
"1","(-1850,2525)","0","pure_quanta_power","I110";
;
CDS_LIB"pure_quanta_power"
HDL_POWER"GND";
"A"15;
%"Q_CAPP"
"1","(-1850,2900)","0","pure_quanta","I112";
;
LOCATION"PC279"
$SEC"1"
CDS_SEC"1"
PACK_TYPE"SMLF"
VOLTAGE"4V"
VALUE"220UF"
TOLERANCE"20%"
MATERIAL"SPCAP"
PART_NUMBER"CH122KM8801"
CDS_LIB"pure_quanta";
"A"
$PN"1"56;
"B"
$PN"2"15;
%"Q_CAP"
"1","(-5525,5325)","0","pure_quanta","I113";
;
LOCATION"PC260_1"
$SEC"1"
CDS_SEC"1"
PART_NUMBER"CH4104K1B00"
MATERIAL"X7R"
TOLERANCE"10%"
VALUE"0.1UF"
VOLTAGE"25V"
PACK_TYPE"0402"
CDS_LIB"pure_quanta";
"B"
$PN"2"53;
"A"
$PN"1"52;
%"Q_CAP"
"1","(-5525,2575)","0","pure_quanta","I114";
;
LOCATION"PC261_2"
$SEC"1"
CDS_SEC"1"
PACK_TYPE"0402"
MATERIAL"X7R"
TOLERANCE"10%"
VALUE"0.1UF"
PART_NUMBER"CH4104K1B00"
VOLTAGE"25V"
CDS_LIB"pure_quanta";
"B"
$PN"2"61;
"A"
$PN"1"14;
%"Q_CAP"
"1","(-7625,2050)","0","pure_quanta","I115";
;
LOCATION"PC257"
$SEC"1"
CDS_SEC"1"
MATERIAL"X6S"
TOLERANCE"10%"
VALUE"2.2UF"
PART_NUMBER"CH5222KEB01"
VOLTAGE"10V"
PACK_TYPE"C0402"
CDS_LIB"pure_quanta";
"B"
$PN"2"1;
"A"
$PN"1"40;
%"UNIVERSAL_GND"
"1","(-7625,1850)","0","pure_quanta_power","I116";
;
CDS_LIB"pure_quanta_power"
HDL_POWER"GND";
"A"1;
%"UNIVERSAL_GND"
"1","(-7275,2350)","0","pure_quanta_power","I117";
;
CDS_LIB"pure_quanta_power"
HDL_POWER"GND";
"A"2;
%"Q_RES"
"2","(-7625,2600)","0","pure_quanta","I118";
;
LOCATION"PR186"
$SEC"1"
CDS_SEC"1"
WATTAGE"1/16W"
MATERIAL"CHIP"
TOLERANCE"1%"
VALUE"2.2"
PART_NUMBER"CS-2202FB00"
PACK_TYPE"0402LF"
CDS_LIB"pure_quanta";
"A"
$PN"1"39;
"B"
$PN"2"40;
%"Q_CAP"
"1","(-7275,2625)","0","pure_quanta","I119";
;
LOCATION"PC259_C0P1_2"
$SEC"1"
CDS_SEC"1"
MATERIAL"X6S"
TOLERANCE"10%"
VALUE"2.2UF"
PART_NUMBER"CH5222KEB01"
VOLTAGE"10V"
PACK_TYPE"C0402"
CDS_LIB"pure_quanta";
"B"
$PN"2"2;
"A"
$PN"1"39;
%"UNIVERSAL_GND"
"1","(-7675,3975)","0","pure_quanta_power","I12";
;
CDS_LIB"pure_quanta_power"
HDL_POWER"GND";
"A"3;
%"VCC_CORE"
"1","(-7625,3000)","0","pure_quanta_power","I120";
;
HDL_POWER"PVDDCR_CPU0_P1_PVCC"
CDS_LIB"pure_quanta_power";
"A"39;
%"Q_CAPP"
"1","(-3150,2900)","0","pure_quanta","I121";
;
LOCATION"PC105"
$SEC"1"
CDS_SEC"1"
VOLTAGE"4V"
TOLERANCE"20%"
VALUE"220UF"
MATERIAL"SPCAP"
PACK_TYPE"SMLF"
PART_NUMBER"CH122KM8801"
CDS_LIB"pure_quanta";
"A"
$PN"1"56;
"B"
$PN"2"15;
%"UNIVERSAL_GND"
"1","(-4850,3550)","0","pure_quanta_power","I123";
;
CDS_LIB"pure_quanta_power"
HDL_POWER"GND";
"A"4;
%"Q_RES"
"2","(-4850,3775)","0","pure_quanta","I124";
;
LOCATION"PR485"
$SEC"1"
CDS_SEC"1"
PART_NUMBER"CS-1504FB00"
MATERIAL"EMPTY"
PACK_TYPE"0402LF"
WATTAGE"1/8W"
TOLERANCE"1%"
VALUE"1.5"
CDS_LIB"pure_quanta";
"A"
$PN"1"47;
"B"
$PN"2"4;
%"Q_CAP"
"1","(-4850,4250)","0","pure_quanta","I125";
;
LOCATION"PC170"
$SEC"1"
CDS_SEC"1"
PART_NUMBER"CH1566K1B09"
VOLTAGE"50V"
MATERIAL"EMPTY"
TOLERANCE"10%"
VALUE"560PF"
PACK_TYPE"C0402"
CDS_LIB"pure_quanta";
"B"
$PN"2"47;
"A"
$PN"1"20;
%"UNIVERSAL_GND"
"1","(-4700,775)","0","pure_quanta_power","I126";
;
CDS_LIB"pure_quanta_power"
HDL_POWER"GND";
"A"5;
%"Q_RES"
"2","(-4700,1000)","0","pure_quanta","I127";
;
LOCATION"PR486"
$SEC"1"
CDS_SEC"1"
WATTAGE"1/8W"
MATERIAL"EMPTY"
TOLERANCE"1%"
VALUE"1.5"
PART_NUMBER"CS-1504FB00"
PACK_TYPE"0402LF"
CDS_LIB"pure_quanta";
"A"
$PN"1"33;
"B"
$PN"2"5;
%"Q_CAP"
"1","(-4700,1500)","0","pure_quanta","I128";
;
LOCATION"PC173"
$SEC"1"
CDS_SEC"1"
MATERIAL"EMPTY"
TOLERANCE"10%"
VALUE"560PF"
PART_NUMBER"CH1566K1B09"
VOLTAGE"50V"
PACK_TYPE"C0402"
CDS_LIB"pure_quanta";
"B"
$PN"2"33;
"A"
$PN"1"49;
%"Q_CAP"
"1","(-8000,4175)","0","pure_quanta","I13";
;
LOCATION"PC254_1"
$SEC"1"
CDS_SEC"1"
MATERIAL"X7R"
TOLERANCE"10%"
VALUE"0.1UF"
PART_NUMBER"CH4104K1B00"
VOLTAGE"25V"
PACK_TYPE"0402"
CDS_LIB"pure_quanta";
"B"
$PN"2"8;
"A"
$PN"1"58;
%"Q_RES"
"1","(-8300,5750)","1","pure_quanta","I130";
;
LOCATION"PR335"
$SEC"1"
CDS_SEC"1"
WATTAGE"1/16W"
MATERIAL"CHIP"
TOLERANCE"5%"
VALUE"0"
PART_NUMBER"CS00002JB38"
PACK_TYPE"0402LF"
CDS_LIB"pure_quanta";
"B"
$PN"2"6;
"A"
$PN"1"57;
%"VCC_CORE"
"1","(-8300,5950)","0","pure_quanta_power","I131";
;
HDL_POWER"P5V_STBY"
CDS_LIB"pure_quanta_power";
"A"6;
%"Q_RES"
"1","(-7950,5750)","1","pure_quanta","I132";
;
LOCATION"PR336"
$SEC"1"
CDS_SEC"1"
WATTAGE"1/16W"
MATERIAL"EMPTY"
TOLERANCE"5%"
VALUE"0"
PART_NUMBER"CS00002JB38"
PACK_TYPE"0402LF"
CDS_LIB"pure_quanta";
"B"
$PN"2"7;
"A"
$PN"1"57;
%"VCC_CORE"
"1","(-7950,5950)","0","pure_quanta_power","I133";
;
HDL_POWER"P3V3_STBY"
CDS_LIB"pure_quanta_power";
"A"7;
%"VCC_CORE"
"1","(-7475,5950)","0","pure_quanta_power","I134";
;
HDL_POWER"PVDDCR_CPU0_P1_PVCC"
CDS_LIB"pure_quanta_power";
"A"57;
%"Q_RES"
"2","(-975,4275)","0","pure_quanta","I135";
;
LOCATION"PR337"
$SEC"1"
CDS_SEC"1"
WATTAGE"1/16W"
MATERIAL"CHIP"
TOLERANCE"1%"
VALUE"1K"
PART_NUMBER"TMP_QCS21002FB24"
PACK_TYPE"0402LF"
CDS_LIB"pure_quanta";
"A"
$PN"1"13;
"B"
$PN"2"23;
%"UNIVERSAL_GND"
"1","(-8000,3900)","0","pure_quanta_power","I14";
;
CDS_LIB"pure_quanta_power"
HDL_POWER"GND";
"A"8;
%"UNIVERSAL_GND"
"1","(-5600,3725)","0","pure_quanta_power","I15";
;
CDS_LIB"pure_quanta_power"
HDL_POWER"GND";
"A"32;
%"Q_RES"
"1","(-4925,4800)","0","pure_quanta","I16";
;
LOCATION"PR189"
$SEC"1"
CDS_SEC"1"
PACK_TYPE"0402LF"
MATERIAL"CHIP"
WATTAGE"1/16W"
TOLERANCE"1%"
VALUE"4.7"
PART_NUMBER"CS-4702FB19"
CDS_LIB"pure_quanta";
"B"
$PN"2"54;
"A"
$PN"1"26;
%"Q_CAP"
"1","(-4100,4675)","0","pure_quanta","I17";
;
LOCATION"PC270"
$SEC"1"
CDS_SEC"1"
VALUE"0.22UF"
PART_NUMBER"CH4223K1B00"
TOLERANCE"10%"
VOLTAGE"16V"
PACK_TYPE"0402"
MATERIAL"X7R"
CDS_LIB"pure_quanta";
"B"
$PN"2"19;
"A"
$PN"1"54;
%"Q_CAP"
"1","(-4250,5325)","0","pure_quanta","I18";
;
LOCATION"PC268_1"
$SEC"1"
CDS_SEC"1"
VOLTAGE"25V"
PART_NUMBER"CH6104KEA00"
PACK_TYPE"C0805"
MATERIAL"X6S"
TOLERANCE"10%"
VALUE"10UF"
CDS_LIB"pure_quanta";
"B"
$PN"2"53;
"A"
$PN"1"52;
%"Q_CAP"
"1","(-4550,5325)","0","pure_quanta","I19";
;
LOCATION"PC266_1"
$SEC"1"
CDS_SEC"1"
VALUE"10UF"
VOLTAGE"25V"
MATERIAL"X6S"
TOLERANCE"10%"
PART_NUMBER"CH6104KEA00"
PACK_TYPE"C0805"
CDS_LIB"pure_quanta";
"B"
$PN"2"53;
"A"
$PN"1"52;
%"Q_CAP"
"1","(-7300,5375)","0","pure_quanta","I2";
;
LOCATION"PC258_C0P1_1"
$SEC"1"
CDS_SEC"1"
PART_NUMBER"CH5222KEB01"
TOLERANCE"10%"
MATERIAL"X6S"
VALUE"2.2UF"
VOLTAGE"10V"
PACK_TYPE"C0402"
CDS_LIB"pure_quanta";
"B"
$PN"2"9;
"A"
$PN"1"57;
%"Q_CAP"
"1","(-4875,5325)","0","pure_quanta","I20";
;
LOCATION"PC264_1"
$SEC"1"
CDS_SEC"1"
MATERIAL"X6S"
TOLERANCE"10%"
VALUE"10UF"
PART_NUMBER"CH6104KEA00"
VOLTAGE"25V"
PACK_TYPE"C0805"
CDS_LIB"pure_quanta";
"B"
$PN"2"53;
"A"
$PN"1"52;
%"Q_CAP"
"1","(-5200,5325)","0","pure_quanta","I21";
;
LOCATION"PC262_1"
$SEC"1"
CDS_SEC"1"
PACK_TYPE"C0402"
MATERIAL"X6S"
TOLERANCE"10%"
VALUE"1UF"
PART_NUMBER"CH5104KEB02"
VOLTAGE"25V"
CDS_LIB"pure_quanta";
"B"
$PN"2"53;
"A"
$PN"1"52;
%"UNIVERSAL_GND"
"1","(-4050,4975)","0","pure_quanta_power","I23";
;
CDS_LIB"pure_quanta_power"
HDL_POWER"GND";
"A"53;
%"Q_INDUCTOR"
"1","(-2950,5525)","0","pure_quanta","I24";
;
LOCATION"PL30"
$SEC"1"
CDS_SEC"1"
MATERIAL"IND"
VALUE"50NH/86A"
PART_NUMBER"CVA50^0MZ09"
PACK_TYPE"SMLF"
CDS_LIB"pure_quanta"
NEEDS_NO_SIZE"TRUE";
"1"
$PN"1"52;
"2"
$PN"2"21;
%"VCC_CORE"
"1","(-4075,5650)","0","pure_quanta_power","I25";
;
HDL_POWER"SW_P12V_STBY_PVDDCR_CPU0_P1_FLT"
CDS_LIB"pure_quanta_power";
"A"52;
%"Q_CAPP"
"1","(-3900,5325)","0","pure_quanta","I26";
;
LOCATION"PC272"
$SEC"1"
CDS_SEC"1"
PART_NUMBER"CC72204MD02"
PACK_TYPE"THLF"
MATERIAL"OSCON"
VOLTAGE"25V"
TOLERANCE"20%"
VALUE"220UF"
CDS_LIB"pure_quanta";
"A"
$PN"1"52;
"B"
$PN"2"53;
%"Q_CAPP"
"1","(-3525,5325)","0","pure_quanta","I27";
;
LOCATION"PC273"
$SEC"1"
CDS_SEC"1"
PART_NUMBER"CC72204MD02"
PACK_TYPE"THLF"
MATERIAL"OSCON"
VOLTAGE"25V"
VALUE"220UF"
TOLERANCE"20%"
CDS_LIB"pure_quanta";
"A"
$PN"1"52;
"B"
$PN"2"53;
%"Q_RES"
"2","(-7650,5350)","0","pure_quanta","I3";
;
LOCATION"PR185"
$SEC"1"
CDS_SEC"1"
WATTAGE"1/16W"
MATERIAL"CHIP"
TOLERANCE"1%"
VALUE"2.2"
PART_NUMBER"CS-2202FB00"
PACK_TYPE"0402LF"
CDS_LIB"pure_quanta";
"A"
$PN"1"57;
"B"
$PN"2"55;
%"VCC_CORE"
"1","(-2725,5650)","0","pure_quanta_power","I30";
;
HDL_POWER"P12V_STBY"
CDS_LIB"pure_quanta_power";
"A"21;
%"Q_INDUCTOR4P_14"
"1","(-3375,4325)","0","pure_quanta","I31";
;
LOCATION"PL28"
$SEC"1"
CDS_SEC"1"
VALUE"150NH"
PART_TYPE"SMLF"
MATERIAL"IND"
PART_NUMBER"CV+15^0TZ04"
CDS_LIB"pure_quanta"
NEEDS_NO_SIZE"TRUE";
"1"
$PN"1"20;
"4"
$PN"4"13;
"3"
$PN"3"22;
"2"
$PN"2"25;
%"Q_CAP"
"1","(-1275,4275)","0","pure_quanta","I32";
;
LOCATION"PC283_1"
$SEC"1"
CDS_SEC"1"
MATERIAL"X6S"
TOLERANCE"20%"
VALUE"22UF"
VOLTAGE"4V"
PACK_TYPE"0805"
CDS_LIB"pure_quanta"
PART_NUMBER"TMP_QCH622KMEA01";
"B"
$PN"2"23;
"A"
$PN"1"13;
%"Q_CAP"
"1","(-1700,4275)","0","pure_quanta","I33";
;
LOCATION"PC281_1"
$SEC"1"
CDS_SEC"1"
MATERIAL"X6S"
TOLERANCE"20%"
VALUE"22UF"
PART_NUMBER"TMP_QCH622KMEA01"
VOLTAGE"4V"
PACK_TYPE"0805"
CDS_LIB"pure_quanta";
"B"
$PN"2"23;
"A"
$PN"1"13;
%"Q_CAP"
"1","(-2075,4275)","0","pure_quanta","I35";
;
LOCATION"PC278"
$SEC"1"
CDS_SEC"1"
MATERIAL"X7R"
TOLERANCE"10%"
VALUE"0.1UF"
PART_NUMBER"CH4104K1B00"
VOLTAGE"25V"
PACK_TYPE"0402"
CDS_LIB"pure_quanta";
"B"
$PN"2"23;
"A"
$PN"1"13;
%"UNIVERSAL_GND"
"1","(-975,3925)","0","pure_quanta_power","I36";
;
CDS_LIB"pure_quanta_power"
HDL_POWER"GND";
"A"23;
%"VCC_CORE"
"1","(-975,4600)","0","pure_quanta_power","I37";
;
HDL_POWER"PVDDCR_CPU0_P1"
CDS_LIB"pure_quanta_power";
"A"13;
%"Q_CAP"
"1","(-7650,4800)","0","pure_quanta","I4";
;
LOCATION"PC256"
$SEC"1"
CDS_SEC"1"
MATERIAL"X6S"
TOLERANCE"10%"
VALUE"2.2UF"
PART_NUMBER"CH5222KEB01"
VOLTAGE"10V"
PACK_TYPE"C0402"
CDS_LIB"pure_quanta";
"B"
$PN"2"10;
"A"
$PN"1"55;
%"Q_RES"
"1","(-4375,3475)","0","pure_quanta","I40";
;
LOCATION"PR191"
$SEC"1"
CDS_SEC"1"
PART_NUMBER"CS00002JB38"
MATERIAL"CHIP"
TOLERANCE"5%"
VALUE"0"
PACK_TYPE"0402LF"
WATTAGE"1/16W"
CDS_LIB"pure_quanta";
"B"
$PN"2"13;
"A"
$PN"1"60;
%"ISL99390FRZTR5935"
"1","(-6150,1700)","0","pure_quanta","I46";
;
LOCATION"PU26"
$SEC"1"
CDS_SEC"1"
PART_TYPE"SMLF"
MATERIAL"IC"
VALUE"ISL99390FRZ-TR5935"
PART_NUMBER"AL099390004"
CDS_LIB"pure_quanta"
CDS_LMAN_SYM_OUTLINE"-300,700,250,-650"
NEEDS_NO_SIZE"TRUE";
"PGND2"
$PN"7_9-20_24"34;
"GL2"
$PN"41"36;
"GL1"
$PN"6"35;
"DNC"
$PN"31"41;
"EN"
$PN"35"40;
"PGND3"
$PN"40"34;
"VOS"
$PN"1"50;
"VIN2"
$PN"30"14;
"PGND1"
$PN"5"34;
"SW"
$PN"10_19"49;
"LSET"
$PN"37"46;
"IOUT"
$PN"38"44;
"TOUT_FLT"
$PN"36"43;
"PVCC"
$PN"4"39;
"PHASE"
$PN"32"51;
"VIN1"
$PN"25_29"14;
"BOOT"
$PN"33"31;
"AGND"
$PN"2"34;
"VCC"
$PN"3"40;
"REFIN"
$PN"39"45;
"PWM"
$PN"34"42;
%"VCC_CORE"
"1","(-1325,1850)","0","pure_quanta_power","I47";
;
HDL_POWER"PVDDCR_CPU0_P1"
CDS_LIB"pure_quanta_power";
"A"17;
%"Q_CAP"
"1","(-1325,1525)","0","pure_quanta","I48";
;
LOCATION"PC282_2"
$SEC"1"
CDS_SEC"1"
MATERIAL"X6S"
TOLERANCE"20%"
VALUE"22UF"
PART_NUMBER"TMP_QCH622KMEA01"
VOLTAGE"4V"
PACK_TYPE"0805"
CDS_LIB"pure_quanta";
"B"
$PN"2"16;
"A"
$PN"1"17;
%"UNIVERSAL_GND"
"1","(-1325,1175)","0","pure_quanta_power","I49";
;
CDS_LIB"pure_quanta_power"
HDL_POWER"GND";
"A"16;
%"UNIVERSAL_GND"
"1","(-7300,5100)","0","pure_quanta_power","I5";
;
CDS_LIB"pure_quanta_power"
HDL_POWER"GND";
"A"9;
%"Q_CAP"
"1","(-1750,1525)","0","pure_quanta","I50";
;
LOCATION"PC280_2"
$SEC"1"
CDS_SEC"1"
MATERIAL"X6S"
TOLERANCE"20%"
VALUE"22UF"
PART_NUMBER"TMP_QCH622KMEA01"
VOLTAGE"4V"
PACK_TYPE"0805"
CDS_LIB"pure_quanta";
"B"
$PN"2"16;
"A"
$PN"1"17;
%"VCC_CORE"
"1","(-4250,2875)","0","pure_quanta_power","I54";
;
HDL_POWER"SW_P12V_STBY_PVDDCR_CPU0_P1_FLT"
CDS_LIB"pure_quanta_power";
"A"14;
%"UNIVERSAL_GND"
"1","(-4250,2225)","0","pure_quanta_power","I56";
;
CDS_LIB"pure_quanta_power"
HDL_POWER"GND";
"A"61;
%"Q_CAP"
"1","(-4250,2575)","0","pure_quanta","I62";
;
LOCATION"PC269_2"
$SEC"1"
CDS_SEC"1"
MATERIAL"X6S"
VALUE"10UF"
PACK_TYPE"C0805"
VOLTAGE"25V"
TOLERANCE"10%"
PART_NUMBER"CH6104KEA00"
CDS_LIB"pure_quanta";
"B"
$PN"2"61;
"A"
$PN"1"14;
%"Q_INDUCTOR4P_14"
"1","(-2925,1575)","0","pure_quanta","I63";
;
LOCATION"PL29"
$SEC"1"
CDS_SEC"1"
PART_TYPE"SMLF"
MATERIAL"IND"
VALUE"150NH"
PART_NUMBER"CV+15^0TZ04"
CDS_LIB"pure_quanta"
NEEDS_NO_SIZE"TRUE";
"1"
$PN"1"49;
"4"
$PN"4"17;
"3"
$PN"3"24;
"2"
$PN"2"48;
%"Q_CAP"
"1","(-4550,2575)","0","pure_quanta","I64";
;
LOCATION"PC267_2"
$SEC"1"
CDS_SEC"1"
PACK_TYPE"C0805"
PART_NUMBER"CH6104KEA00"
TOLERANCE"10%"
VOLTAGE"25V"
MATERIAL"X6S"
VALUE"10UF"
CDS_LIB"pure_quanta";
"B"
$PN"2"61;
"A"
$PN"1"14;
%"Q_CAP"
"1","(-4875,2575)","0","pure_quanta","I65";
;
LOCATION"PC265_2"
$SEC"1"
CDS_SEC"1"
PACK_TYPE"C0805"
MATERIAL"X6S"
TOLERANCE"10%"
VALUE"10UF"
PART_NUMBER"CH6104KEA00"
VOLTAGE"25V"
CDS_LIB"pure_quanta";
"B"
$PN"2"61;
"A"
$PN"1"14;
%"Q_CAP"
"1","(-5200,2575)","0","pure_quanta","I66";
;
LOCATION"PC263_2"
$SEC"1"
CDS_SEC"1"
PART_NUMBER"CH5104KEB02"
PACK_TYPE"C0402"
MATERIAL"X6S"
TOLERANCE"10%"
VALUE"1UF"
VOLTAGE"25V"
CDS_LIB"pure_quanta";
"B"
$PN"2"61;
"A"
$PN"1"14;
%"Q_CAP"
"1","(-3725,1925)","0","pure_quanta","I67";
;
LOCATION"PC271"
$SEC"1"
CDS_SEC"1"
PACK_TYPE"0402"
MATERIAL"X7R"
TOLERANCE"10%"
VALUE"0.22UF"
PART_NUMBER"CH4223K1B00"
VOLTAGE"16V"
CDS_LIB"pure_quanta";
"B"
$PN"2"51;
"A"
$PN"1"18;
%"Q_RES"
"1","(-4300,625)","0","pure_quanta","I68";
;
LOCATION"PR192"
$SEC"1"
CDS_SEC"1"
WATTAGE"1/16W"
MATERIAL"CHIP"
TOLERANCE"5%"
VALUE"0"
PART_NUMBER"CS00002JB38"
PACK_TYPE"0402LF"
CDS_LIB"pure_quanta";
"B"
$PN"2"17;
"A"
$PN"1"50;
%"UNIVERSAL_GND"
"1","(-7650,4600)","0","pure_quanta_power","I7";
;
CDS_LIB"pure_quanta_power"
HDL_POWER"GND";
"A"10;
%"Q_RES"
"1","(-4725,2050)","0","pure_quanta","I71";
;
LOCATION"PR190"
$SEC"1"
CDS_SEC"1"
TOLERANCE"1%"
MATERIAL"CHIP"
WATTAGE"1/16W"
PACK_TYPE"0402LF"
VALUE"4.7"
PART_NUMBER"CS-4702FB19"
CDS_LIB"pure_quanta";
"B"
$PN"2"18;
"A"
$PN"1"31;
%"Q_RES"
"1","(-7325,1400)","0","pure_quanta","I75";
;
LOCATION"PR188"
$SEC"1"
CDS_SEC"1"
WATTAGE"1/16W"
MATERIAL"EMPTY"
TOLERANCE"1%"
VALUE"8.87K"
PART_NUMBER"CS28872FB01"
PACK_TYPE"0402LF"
CDS_LIB"pure_quanta";
"B"
$PN"2"46;
"A"
$PN"1"11;
%"UNIVERSAL_GND"
"1","(-7650,1225)","0","pure_quanta_power","I84";
;
CDS_LIB"pure_quanta_power"
HDL_POWER"GND";
"A"11;
%"UNIVERSAL_GND"
"1","(-7975,1150)","0","pure_quanta_power","I85";
;
CDS_LIB"pure_quanta_power"
HDL_POWER"GND";
"A"12;
%"Q_CAP"
"1","(-7975,1425)","0","pure_quanta","I86";
;
LOCATION"PC255_2"
$SEC"1"
CDS_SEC"1"
MATERIAL"X7R"
TOLERANCE"10%"
VALUE"0.1UF"
PART_NUMBER"CH4104K1B00"
VOLTAGE"25V"
PACK_TYPE"0402"
CDS_LIB"pure_quanta";
"B"
$PN"2"12;
"A"
$PN"1"45;
%"UNIVERSAL_GND"
"1","(-5600,975)","0","pure_quanta_power","I88";
;
CDS_LIB"pure_quanta_power"
HDL_POWER"GND";
"A"34;
%"Q_CAPP"
"1","(-2150,2900)","0","pure_quanta","I92";
;
LOCATION"PC277"
$SEC"1"
CDS_SEC"1"
VOLTAGE"4V"
VALUE"220UF"
TOLERANCE"20%"
MATERIAL"SPCAP"
PACK_TYPE"SMLF"
PART_NUMBER"CH122KM8801"
CDS_LIB"pure_quanta";
"A"
$PN"1"56;
"B"
$PN"2"15;
END.
